(kicad_pcb
	(version 20260206)
	(generator "pcbnew")
	(generator_version "10.0")
	(general
		(thickness 1.6)
		(legacy_teardrops no)
	)
	(paper "A4")
	(title_block
		(title "03242023_DA0F0TMBIJ0_F0T_Motherboard_J_brd_V01_OCP.brd")
		(comment 1 "Grand Teton / footprint 3039 of 6105 (U2), pads 1928-2035 of 4677")
	)
	(layers
		(0 "F.Cu" signal "TOP")
		(4 "In1.Cu" signal "GND")
		(6 "In2.Cu" signal "IN1")
		(8 "In3.Cu" signal "GND1")
		(10 "In4.Cu" signal "IN2")
		(12 "In5.Cu" signal "GND2")
		(14 "In6.Cu" signal "IN3")
		(16 "In7.Cu" signal "GND3")
		(18 "In8.Cu" signal "VCC")
		(20 "In9.Cu" signal "VCC1")
		(22 "In10.Cu" signal "GND4")
		(24 "In11.Cu" signal "IN4")
		(26 "In12.Cu" signal "GND5")
		(28 "In13.Cu" signal "IN5")
		(30 "In14.Cu" signal "GND6")
		(32 "In15.Cu" signal "IN6")
		(34 "In16.Cu" signal "GND7")
		(2 "B.Cu" signal "BOTTOM")
		(9 "F.Adhes" user "F.Adhesive")
		(11 "B.Adhes" user "B.Adhesive")
		(13 "F.Paste" user "Package Geometry/Pastemask Top")
		(15 "B.Paste" user "Package Geometry/Pastemask Bottom")
		(5 "F.SilkS" user "Ref Des/Silkscreen Top")
		(7 "B.SilkS" user "Ref Des/Silkscreen Bottom")
		(1 "F.Mask" user "Board Geometry/Soldermask Top")
		(3 "B.Mask" user "Board Geometry/Soldermask Bottom")
		(17 "Dwgs.User" user "User.Drawings")
		(19 "Cmts.User" user "User.Comments")
		(21 "Eco1.User" user "User.Eco1")
		(23 "Eco2.User" user "User.Eco2")
		(25 "Edge.Cuts" user "Board Geometry/Outline")
		(27 "Margin" user)
		(31 "F.CrtYd" user "Package Geometry/Place Bound Top")
		(29 "B.CrtYd" user "Package Geometry/Place Bound Bottom")
		(35 "F.Fab" user "Ref Des/Assembly Top")
		(33 "B.Fab" user "Ref Des/Assembly Bottom")
	)
	(footprint ""
		(layer "F.Cu")
		(at 359.870248 -251.76988 90)
		(property "Reference" "U2"
			(at -74.416158 -44.488608 0)
			(unlocked yes)
			(layer "F.SilkS")
			(effects
				(font
					(size 1.6002 1.1938)
					(thickness 0.1524)
				)
				(justify left)
			)
		)
		(property "Value" ""
			(at 0 0 90)
			(layer "F.Fab")
			(effects
				(font
					(size 1.27 1.27)
				)
			)
		)
		(duplicate_pad_numbers_are_jumpers no)
		(pad "CG68" smd circle
			(at 18.705576 4.049268 270)
			(size 0.4318 0.4318)
			(layers "F.Cu" "F.Mask" "F.Paste")
			(net "PVPP_HBM_CPU0")
		)
		(pad "CG70" smd circle
			(at 20.333462 4.049268 270)
			(size 0.4318 0.4318)
			(layers "F.Cu" "F.Mask" "F.Paste")
			(net "GND")
		)
		(pad "CG72" smd circle
			(at 21.961094 4.049268 270)
			(size 0.4318 0.4318)
			(layers "F.Cu" "F.Mask" "F.Paste")
			(net "GND")
		)
		(pad "CG74" smd circle
			(at 23.58898 4.049268 270)
			(size 0.4318 0.4318)
			(layers "F.Cu" "F.Mask" "F.Paste")
			(net "GND")
		)
		(pad "CG76" smd circle
			(at 25.216612 4.049268 270)
			(size 0.4318 0.4318)
			(layers "F.Cu" "F.Mask" "F.Paste")
			(net "Net_690")
		)
		(pad "CG78" smd circle
			(at 26.844498 4.049268 270)
			(size 0.4318 0.4318)
			(layers "F.Cu" "F.Mask" "F.Paste")
			(net "GND")
		)
		(pad "CG80" smd circle
			(at 28.472384 4.049268 270)
			(size 0.4318 0.4318)
			(layers "F.Cu" "F.Mask" "F.Paste")
			(net "PVCCIN_CPU0")
		)
		(pad "CG82" smd circle
			(at 30.100016 4.049268 270)
			(size 0.4318 0.4318)
			(layers "F.Cu" "F.Mask" "F.Paste")
			(net "PVCCIN_CPU0")
		)
		(pad "CG84" smd circle
			(at 31.727902 4.049268 270)
			(size 0.4318 0.4318)
			(layers "F.Cu" "F.Mask" "F.Paste")
			(net "PVCCIN_CPU0")
		)
		(pad "CG86" smd circle
			(at 33.355534 4.049268 270)
			(size 0.4318 0.4318)
			(layers "F.Cu" "F.Mask" "F.Paste")
			(net "PVCCIN_CPU0")
		)
		(pad "CG88" smd circle
			(at 34.98342 4.049268 270)
			(size 0.4318 0.4318)
			(layers "F.Cu" "F.Mask" "F.Paste")
			(net "PVCCIN_CPU0")
		)
		(pad "CG90" smd circle
			(at 36.611306 4.049268 270)
			(size 0.4318 0.4318)
			(layers "F.Cu" "F.Mask" "F.Paste")
			(net "PVCCIN_CPU0")
		)
		(pad "CH2" smd circle
			(at -36.611306 4.408932 270)
			(size 0.4318 0.4318)
			(layers "F.Cu" "F.Mask" "F.Paste")
			(net "UPI_CPU1_CPU0_P0P1_DP<20>")
		)
		(pad "CH4" smd circle
			(at -34.98342 4.408932 270)
			(size 0.4318 0.4318)
			(layers "F.Cu" "F.Mask" "F.Paste")
			(net "GND")
		)
		(pad "CH6" smd circle
			(at -33.355534 4.408932 270)
			(size 0.4318 0.4318)
			(layers "F.Cu" "F.Mask" "F.Paste")
			(net "UPI_CPU0_CPU1_P1P0_DP<19>")
		)
		(pad "CH8" smd circle
			(at -31.727902 4.408932 270)
			(size 0.4318 0.4318)
			(layers "F.Cu" "F.Mask" "F.Paste")
			(net "GND")
		)
		(pad "CH10" smd circle
			(at -30.100016 4.408932 270)
			(size 0.4318 0.4318)
			(layers "F.Cu" "F.Mask" "F.Paste")
			(net "P5E_CPU0_PE1_RX_DP<3>")
		)
		(pad "CH12" smd circle
			(at -28.472384 4.408932 270)
			(size 0.4318 0.4318)
			(layers "F.Cu" "F.Mask" "F.Paste")
			(net "GND")
		)
		(pad "CH14" smd circle
			(at -26.844498 4.408932 270)
			(size 0.4318 0.4318)
			(layers "F.Cu" "F.Mask" "F.Paste")
			(net "P5E_CPU0_PE1_TX_DP<3>")
		)
		(pad "CH16" smd circle
			(at -25.216612 4.408932 270)
			(size 0.4318 0.4318)
			(layers "F.Cu" "F.Mask" "F.Paste")
			(net "GND")
		)
		(pad "CH18" smd circle
			(at -23.58898 4.408932 270)
			(size 0.4318 0.4318)
			(layers "F.Cu" "F.Mask" "F.Paste")
			(net "DMI_CPU0_PCH_TX_DP<5>")
		)
		(pad "CH20" smd circle
			(at -21.961094 4.408932 270)
			(size 0.4318 0.4318)
			(layers "F.Cu" "F.Mask" "F.Paste")
			(net "GND")
		)
		(pad "CH22" smd circle
			(at -20.333462 4.408932 270)
			(size 0.4318 0.4318)
			(layers "F.Cu" "F.Mask" "F.Paste")
			(net "PD_CPU0_ENH_MCECC_DIS")
		)
		(pad "CH24" smd circle
			(at -18.705576 4.408932 270)
			(size 0.4318 0.4318)
			(layers "F.Cu" "F.Mask" "F.Paste")
			(net "TP_H_SBLINK6_CPU0_PMSYNC")
		)
		(pad "CH26" smd circle
			(at -17.07769 4.408932 270)
			(size 0.4318 0.4318)
			(layers "F.Cu" "F.Mask" "F.Paste")
			(net "TP_H_SBLINK3_CPU0_PMSYNC")
		)
		(pad "CH61" smd circle
			(at 13.008356 4.518914 270)
			(size 0.4318 0.4318)
			(layers "F.Cu" "F.Mask" "F.Paste")
			(net "TP_CPU0_SPARE9")
		)
		(pad "CH63" smd circle
			(at 14.635988 4.518914 270)
			(size 0.4318 0.4318)
			(layers "F.Cu" "F.Mask" "F.Paste")
			(net "TP_SGPIO_S3M_CPU0_GSXDIN")
		)
		(pad "CH65" smd circle
			(at 16.263874 4.518914 270)
			(size 0.4318 0.4318)
			(layers "F.Cu" "F.Mask" "F.Paste")
			(net "PU_S3M_CPU0_CPLD_STATUS")
		)
		(pad "CH67" smd circle
			(at 17.89176 4.518914 270)
			(size 0.4318 0.4318)
			(layers "F.Cu" "F.Mask" "F.Paste")
			(net "GND")
		)
		(pad "CH69" smd circle
			(at 19.519392 4.518914 270)
			(size 0.4318 0.4318)
			(layers "F.Cu" "F.Mask" "F.Paste")
			(net "NC_CPU0_MDFI_DIE11_EW1")
		)
		(pad "CH71" smd circle
			(at 21.147278 4.518914 270)
			(size 0.4318 0.4318)
			(layers "F.Cu" "F.Mask" "F.Paste")
			(net "TP_PWRGD_S0_PWROK_CPU0_LVC1")
		)
		(pad "CH73" smd circle
			(at 22.77491 4.518914 270)
			(size 0.4318 0.4318)
			(layers "F.Cu" "F.Mask" "F.Paste")
			(net "GND")
		)
		(pad "CH75" smd circle
			(at 24.402796 4.518914 270)
			(size 0.4318 0.4318)
			(layers "F.Cu" "F.Mask" "F.Paste")
			(net "Net_664")
		)
		(pad "CH77" smd circle
			(at 26.030682 4.518914 270)
			(size 0.4318 0.4318)
			(layers "F.Cu" "F.Mask" "F.Paste")
			(net "Net_692")
		)
		(pad "CH79" smd circle
			(at 27.658314 4.518914 270)
			(size 0.4318 0.4318)
			(layers "F.Cu" "F.Mask" "F.Paste")
			(net "GND")
		)
		(pad "CH81" smd circle
			(at 29.2862 4.518914 270)
			(size 0.4318 0.4318)
			(layers "F.Cu" "F.Mask" "F.Paste")
			(net "PVCCIN_CPU0")
		)
		(pad "CH83" smd circle
			(at 30.914086 4.518914 270)
			(size 0.4318 0.4318)
			(layers "F.Cu" "F.Mask" "F.Paste")
			(net "GND")
		)
		(pad "CH85" smd circle
			(at 32.541718 4.518914 270)
			(size 0.4318 0.4318)
			(layers "F.Cu" "F.Mask" "F.Paste")
			(net "GND")
		)
		(pad "CH87" smd circle
			(at 34.169604 4.518914 270)
			(size 0.4318 0.4318)
			(layers "F.Cu" "F.Mask" "F.Paste")
			(net "GND")
		)
		(pad "CH89" smd circle
			(at 35.797236 4.518914 270)
			(size 0.4318 0.4318)
			(layers "F.Cu" "F.Mask" "F.Paste")
			(net "GND")
		)
		(pad "CH91" smd oval
			(at 37.425122 4.518914)
			(size 0.381 0.4826)
			(drill
				(offset 0 -0.0508)
			)
			(layers "F.Cu" "F.Mask" "F.Paste")
			(net "PVCCIN_CPU0")
		)
		(pad "CJ1" smd oval
			(at -37.425122 4.879086 180)
			(size 0.381 0.4826)
			(drill
				(offset 0 -0.0508)
			)
			(layers "F.Cu" "F.Mask" "F.Paste")
			(net "UPI_CPU1_CPU0_P0P1_DP<19>")
		)
		(pad "CJ3" smd circle
			(at -35.797236 4.879086 270)
			(size 0.4318 0.4318)
			(layers "F.Cu" "F.Mask" "F.Paste")
			(net "PVCCINFAON_CPU0")
		)
		(pad "CJ5" smd circle
			(at -34.169604 4.879086 270)
			(size 0.4318 0.4318)
			(layers "F.Cu" "F.Mask" "F.Paste")
			(net "UPI_CPU0_CPU1_P1P0_DP<18>")
		)
		(pad "CJ7" smd circle
			(at -32.541718 4.879086 270)
			(size 0.4318 0.4318)
			(layers "F.Cu" "F.Mask" "F.Paste")
			(net "PVCCINFAON_CPU0")
		)
		(pad "CJ9" smd circle
			(at -30.914086 4.879086 270)
			(size 0.4318 0.4318)
			(layers "F.Cu" "F.Mask" "F.Paste")
			(net "P5E_CPU0_PE1_RX_DP<2>")
		)
		(pad "CJ11" smd circle
			(at -29.2862 4.879086 270)
			(size 0.4318 0.4318)
			(layers "F.Cu" "F.Mask" "F.Paste")
			(net "PVCCINFAON_CPU0")
		)
		(pad "CJ13" smd circle
			(at -27.658314 4.879086 270)
			(size 0.4318 0.4318)
			(layers "F.Cu" "F.Mask" "F.Paste")
			(net "P5E_CPU0_PE1_TX_DN<3>")
		)
		(pad "CJ15" smd circle
			(at -26.030682 4.879086 270)
			(size 0.4318 0.4318)
			(layers "F.Cu" "F.Mask" "F.Paste")
			(net "PVCCINFAON_CPU0")
		)
		(pad "CJ17" smd circle
			(at -24.402796 4.879086 270)
			(size 0.4318 0.4318)
			(layers "F.Cu" "F.Mask" "F.Paste")
			(net "DMI_CPU0_PCH_TX_DN<5>")
		)
		(pad "CJ19" smd circle
			(at -22.77491 4.879086 270)
			(size 0.4318 0.4318)
			(layers "F.Cu" "F.Mask" "F.Paste")
			(net "PVCCINFAON_CPU0")
		)
		(pad "CJ21" smd circle
			(at -21.147278 4.879086 270)
			(size 0.4318 0.4318)
			(layers "F.Cu" "F.Mask" "F.Paste")
			(net "TP_IBL_GRST_WARN_PLD_R_N")
		)
		(pad "CJ23" smd circle
			(at -19.519392 4.879086 270)
			(size 0.4318 0.4318)
			(layers "F.Cu" "F.Mask" "F.Paste")
			(net "TP_I2C_S3M_RTC_CPU0_SDA")
		)
		(pad "CJ25" smd circle
			(at -17.89176 4.879086 270)
			(size 0.4318 0.4318)
			(layers "F.Cu" "F.Mask" "F.Paste")
			(net "TP_I2C_S3M_RTC_CPU0_ALERT_N")
		)
		(pad "CJ60" smd circle
			(at 12.19454 4.989068 270)
			(size 0.4318 0.4318)
			(layers "F.Cu" "F.Mask" "F.Paste")
			(net "GND")
		)
		(pad "CJ62" smd circle
			(at 13.822426 4.989068 270)
			(size 0.4318 0.4318)
			(layers "F.Cu" "F.Mask" "F.Paste")
			(net "NC_CPU0_VIEWPIN_DIE11<0>")
		)
		(pad "CJ64" smd circle
			(at 15.450058 4.989068 270)
			(size 0.4318 0.4318)
			(layers "F.Cu" "F.Mask" "F.Paste")
			(net "PU_S3M_CPU0_CPLD_CONFD")
		)
		(pad "CJ66" smd circle
			(at 17.07769 4.989068 270)
			(size 0.4318 0.4318)
			(layers "F.Cu" "F.Mask" "F.Paste")
			(net "TP_SGPIO_S3M_CPU0_GSXDLOAD_R")
		)
		(pad "CJ68" smd circle
			(at 18.705576 4.989068 270)
			(size 0.4318 0.4318)
			(layers "F.Cu" "F.Mask" "F.Paste")
			(net "NC_CPU0_MDFI_DIE11_NS0")
		)
		(pad "CJ70" smd circle
			(at 20.333462 4.989068 270)
			(size 0.4318 0.4318)
			(layers "F.Cu" "F.Mask" "F.Paste")
			(net "NC_CPU0_MDFI_DIE11_EW0")
		)
		(pad "CJ72" smd circle
			(at 21.961094 4.989068 270)
			(size 0.4318 0.4318)
			(layers "F.Cu" "F.Mask" "F.Paste")
			(net "PUD_XTAL_CPU0_MODE1")
		)
		(pad "CJ74" smd circle
			(at 23.58898 4.989068 270)
			(size 0.4318 0.4318)
			(layers "F.Cu" "F.Mask" "F.Paste")
			(net "Net_687")
		)
		(pad "CJ76" smd circle
			(at 25.216612 4.989068 270)
			(size 0.4318 0.4318)
			(layers "F.Cu" "F.Mask" "F.Paste")
			(net "GND")
		)
		(pad "CJ78" smd circle
			(at 26.844498 4.989068 270)
			(size 0.4318 0.4318)
			(layers "F.Cu" "F.Mask" "F.Paste")
			(net "Net_668")
		)
		(pad "CJ80" smd circle
			(at 28.472384 4.989068 270)
			(size 0.4318 0.4318)
			(layers "F.Cu" "F.Mask" "F.Paste")
			(net "GND")
		)
		(pad "CJ82" smd circle
			(at 30.100016 4.989068 270)
			(size 0.4318 0.4318)
			(layers "F.Cu" "F.Mask" "F.Paste")
			(net "PVCCIN_CPU0")
		)
		(pad "CJ84" smd circle
			(at 31.727902 4.989068 270)
			(size 0.4318 0.4318)
			(layers "F.Cu" "F.Mask" "F.Paste")
			(net "PVCCIN_CPU0")
		)
		(pad "CJ86" smd circle
			(at 33.355534 4.989068 270)
			(size 0.4318 0.4318)
			(layers "F.Cu" "F.Mask" "F.Paste")
			(net "PVCCIN_CPU0")
		)
		(pad "CJ88" smd circle
			(at 34.98342 4.989068 270)
			(size 0.4318 0.4318)
			(layers "F.Cu" "F.Mask" "F.Paste")
			(net "PVCCIN_CPU0")
		)
		(pad "CJ90" smd circle
			(at 36.611306 4.989068 270)
			(size 0.4318 0.4318)
			(layers "F.Cu" "F.Mask" "F.Paste")
			(net "PVCCIN_CPU0")
		)
		(pad "CK2" smd circle
			(at -36.611306 5.348732 270)
			(size 0.4318 0.4318)
			(layers "F.Cu" "F.Mask" "F.Paste")
			(net "UPI_CPU1_CPU0_P0P1_DN<19>")
		)
		(pad "CK4" smd circle
			(at -34.98342 5.348732 270)
			(size 0.4318 0.4318)
			(layers "F.Cu" "F.Mask" "F.Paste")
			(net "GND")
		)
		(pad "CK6" smd circle
			(at -33.355534 5.348732 270)
			(size 0.4318 0.4318)
			(layers "F.Cu" "F.Mask" "F.Paste")
			(net "UPI_CPU0_CPU1_P1P0_DN<18>")
		)
		(pad "CK8" smd circle
			(at -31.727902 5.348732 270)
			(size 0.4318 0.4318)
			(layers "F.Cu" "F.Mask" "F.Paste")
			(net "GND")
		)
		(pad "CK10" smd circle
			(at -30.100016 5.348732 270)
			(size 0.4318 0.4318)
			(layers "F.Cu" "F.Mask" "F.Paste")
			(net "P5E_CPU0_PE1_RX_DN<2>")
		)
		(pad "CK12" smd circle
			(at -28.472384 5.348732 270)
			(size 0.4318 0.4318)
			(layers "F.Cu" "F.Mask" "F.Paste")
			(net "GND")
		)
		(pad "CK14" smd circle
			(at -26.844498 5.348732 270)
			(size 0.4318 0.4318)
			(layers "F.Cu" "F.Mask" "F.Paste")
			(net "P5E_CPU0_PE1_TX_DN<2>")
		)
		(pad "CK16" smd circle
			(at -25.216612 5.348732 270)
			(size 0.4318 0.4318)
			(layers "F.Cu" "F.Mask" "F.Paste")
			(net "GND")
		)
		(pad "CK18" smd circle
			(at -23.58898 5.348732 270)
			(size 0.4318 0.4318)
			(layers "F.Cu" "F.Mask" "F.Paste")
			(net "DMI_CPU0_PCH_TX_DN<6>")
		)
		(pad "CK20" smd circle
			(at -21.961094 5.348732 270)
			(size 0.4318 0.4318)
			(layers "F.Cu" "F.Mask" "F.Paste")
			(net "GND")
		)
		(pad "CK22" smd circle
			(at -20.333462 5.348732 270)
			(size 0.4318 0.4318)
			(layers "F.Cu" "F.Mask" "F.Paste")
			(net "TP_FM_IBL_SYS_RST_CPU0_N")
		)
		(pad "CK24" smd circle
			(at -18.705576 5.348732 270)
			(size 0.4318 0.4318)
			(layers "F.Cu" "F.Mask" "F.Paste")
			(net "TP_CPU0_PWRBTN_N")
		)
		(pad "CK26" smd circle
			(at -17.07769 5.348732 270)
			(size 0.4318 0.4318)
			(layers "F.Cu" "F.Mask" "F.Paste")
			(net "GND")
		)
		(pad "CK61" smd circle
			(at 13.008356 5.458714 270)
			(size 0.4318 0.4318)
			(layers "F.Cu" "F.Mask" "F.Paste")
			(net "TP_CPU0_SPARE8")
		)
		(pad "CK63" smd circle
			(at 14.635988 5.458714 270)
			(size 0.4318 0.4318)
			(layers "F.Cu" "F.Mask" "F.Paste")
			(net "GND")
		)
		(pad "CK65" smd circle
			(at 16.263874 5.458714 270)
			(size 0.4318 0.4318)
			(layers "F.Cu" "F.Mask" "F.Paste")
			(net "FM_S3M_CPU0_CPLD_CONFIG_N")
		)
		(pad "CK67" smd circle
			(at 17.89176 5.458714 270)
			(size 0.4318 0.4318)
			(layers "F.Cu" "F.Mask" "F.Paste")
			(net "NC_CPU0_MDFI_DIE11_NS1")
		)
		(pad "CK69" smd circle
			(at 19.519392 5.458714 270)
			(size 0.4318 0.4318)
			(layers "F.Cu" "F.Mask" "F.Paste")
			(net "GND")
		)
		(pad "CK71" smd circle
			(at 21.147278 5.458714 270)
			(size 0.4318 0.4318)
			(layers "F.Cu" "F.Mask" "F.Paste")
			(net "PU_CPU0_UPI3_AC_COUPLING")
		)
		(pad "CK73" smd circle
			(at 22.77491 5.458714 270)
			(size 0.4318 0.4318)
			(layers "F.Cu" "F.Mask" "F.Paste")
			(net "PVCCFA_EHV_FIVRA_CPU0")
		)
		(pad "CK75" smd circle
			(at 24.402796 5.458714 270)
			(size 0.4318 0.4318)
			(layers "F.Cu" "F.Mask" "F.Paste")
			(net "Net_663")
		)
		(pad "CK77" smd circle
			(at 26.030682 5.458714 270)
			(size 0.4318 0.4318)
			(layers "F.Cu" "F.Mask" "F.Paste")
			(net "Net_693")
		)
		(pad "CK79" smd circle
			(at 27.658314 5.458714 270)
			(size 0.4318 0.4318)
			(layers "F.Cu" "F.Mask" "F.Paste")
			(net "PVCCFA_EHV_FIVRA_CPU0")
		)
		(pad "CK81" smd circle
			(at 29.2862 5.458714 270)
			(size 0.4318 0.4318)
			(layers "F.Cu" "F.Mask" "F.Paste")
			(net "GND")
		)
		(pad "CK83" smd circle
			(at 30.914086 5.458714 270)
			(size 0.4318 0.4318)
			(layers "F.Cu" "F.Mask" "F.Paste")
			(net "PVCCIN_CPU0")
		)
		(pad "CK85" smd circle
			(at 32.541718 5.458714 270)
			(size 0.4318 0.4318)
			(layers "F.Cu" "F.Mask" "F.Paste")
			(net "PVCCIN_CPU0")
		)
		(pad "CK87" smd circle
			(at 34.169604 5.458714 270)
			(size 0.4318 0.4318)
			(layers "F.Cu" "F.Mask" "F.Paste")
			(net "PVCCIN_CPU0")
		)
		(pad "CK89" smd circle
			(at 35.797236 5.458714 270)
			(size 0.4318 0.4318)
			(layers "F.Cu" "F.Mask" "F.Paste")
			(net "PVCCIN_CPU0")
		)
		(pad "CK91" smd oval
			(at 37.425122 5.458714)
			(size 0.381 0.4826)
			(drill
				(offset 0 -0.0508)
			)
			(layers "F.Cu" "F.Mask" "F.Paste")
			(net "PVCCIN_CPU0")
		)
		(pad "CL1" smd oval
			(at -37.425122 5.818886 180)
			(size 0.381 0.4826)
			(drill
				(offset 0 -0.0508)
			)
			(layers "F.Cu" "F.Mask" "F.Paste")
			(net "GND")
		)
		(pad "CL3" smd circle
			(at -35.797236 5.818886 270)
			(size 0.4318 0.4318)
			(layers "F.Cu" "F.Mask" "F.Paste")
			(net "UPI_CPU1_CPU0_P0P1_DN<18>")
		)
		(pad "CL5" smd circle
			(at -34.169604 5.818886 270)
			(size 0.4318 0.4318)
			(layers "F.Cu" "F.Mask" "F.Paste")
			(net "GND")
		)
		(pad "CL7" smd circle
			(at -32.541718 5.818886 270)
			(size 0.4318 0.4318)
			(layers "F.Cu" "F.Mask" "F.Paste")
			(net "UPI_CPU0_CPU1_P1P0_DN<17>")
		)
		(pad "CL9" smd circle
			(at -30.914086 5.818886 270)
			(size 0.4318 0.4318)
			(layers "F.Cu" "F.Mask" "F.Paste")
			(net "GND")
		)
		(pad "CL11" smd circle
			(at -29.2862 5.818886 270)
			(size 0.4318 0.4318)
			(layers "F.Cu" "F.Mask" "F.Paste")
			(net "P5E_CPU0_PE1_RX_DN<1>")
		)
		(pad "CL13" smd circle
			(at -27.658314 5.818886 270)
			(size 0.4318 0.4318)
			(layers "F.Cu" "F.Mask" "F.Paste")
			(net "GND")
		)
		(pad "CL15" smd circle
			(at -26.030682 5.818886 270)
			(size 0.4318 0.4318)
			(layers "F.Cu" "F.Mask" "F.Paste")
			(net "P5E_CPU0_PE1_TX_DP<2>")
		)
		(pad "CL17" smd circle
			(at -24.402796 5.818886 270)
			(size 0.4318 0.4318)
			(layers "F.Cu" "F.Mask" "F.Paste")
			(net "GND")
		)
	)
)
